# S9S_MB_2U (Grand Teton) — schematic netlist excerpt (pin names and nets, part order shuffled) for the footprints in the layout excerpt that follows; sources: Cadence DE-HDL packaged netlist, KiCad conversion of 03242023_DA0F0TMBIJ0_F0T_Motherboard_J_brd_V01_OCP.brd

J31  SCONN288_ADR50017P130CC  SCONN288_ADR50017-P130CC IO  pkg DDR288S_1-1VXB  page 112
  VIN_BULK0  = P12V_S3_AUX_CPU1_NVDIMM
  RFU0  = TP_CHH_CPU1_DIMM1_FRU_0
  VIN_MGMT  = P3V3_AUX
  HSCL  = I3C_SPD_DDREFGH_CPU1_LVC1_SCL_6
  HSDA  = I3C_SPD_DDREFGH_CPU1_LVC1_SDA
  VSS0  = GND
  DQ0_A  = M_H_CPU1_SA_DQ<0>
  VSS1  = GND
  DQ1_A  = M_H_CPU1_SA_DQ<1>
  VSS2  = GND
  DQS0_A_T  = M_H_CPU1_SA_DQS_DP<0>
  DQS0_A_C  = M_H_CPU1_SA_DQS_DN<0>
  VSS3  = GND
  DQ4_A  = M_H_CPU1_SA_DQ<4>
  VSS4  = GND
  DQ5_A  = M_H_CPU1_SA_DQ<5>
  VSS5  = GND
  DQ8_A  = M_H_CPU1_SA_DQ<8>
  VSS6  = GND
  DQ9_A  = M_H_CPU1_SA_DQ<9>
  VSS7  = GND
  DQS1_A_T  = M_H_CPU1_SA_DQS_DP<1>
  DQS1_A_C  = M_H_CPU1_SA_DQS_DN<1>
  VSS8  = GND
  DQ12_A  = M_H_CPU1_SA_DQ<12>
  VSS9  = GND
  DQ13_A  = M_H_CPU1_SA_DQ<13>
  VSS10  = GND
  DQ16_A  = M_H_CPU1_SA_DQ<16>
  VSS11  = GND
  DQ17_A  = M_H_CPU1_SA_DQ<17>
  VSS12  = GND
  DQS2_A_T  = M_H_CPU1_SA_DQS_DP<2>
  DQS2_A_C  = M_H_CPU1_SA_DQS_DN<2>
  VSS13  = GND
  DQ20_A  = M_H_CPU1_SA_DQ<20>
  VSS14  = GND
  DQ21_A  = M_H_CPU1_SA_DQ<21>
  VSS15  = GND
  DQ24_A  = M_H_CPU1_SA_DQ<24>
  VSS16  = GND
  DQ25_A  = M_H_CPU1_SA_DQ<25>
  VSS17  = GND
  DQS3_A_T  = M_H_CPU1_SA_DQS_DP<3>
  DQS3_A_C  = M_H_CPU1_SA_DQS_DN<3>
  VSS18  = GND
  DQ28_A  = M_H_CPU1_SA_DQ<28>
  VSS19  = GND
  DQ29_A  = M_H_CPU1_SA_DQ<29>
  VSS20  = GND
  CB0_A  = M_H_CPU1_SA_CB<0>
  VSS21  = GND
  CB1_A  = M_H_CPU1_SA_CB<1>
  VSS22  = GND
  DQS4_A_T  = M_H_CPU1_SA_DQS_DP<4>
  DQS4_A_C  = M_H_CPU1_SA_DQS_DN<4>
  VSS23  = GND
  CB4_A  = M_H_CPU1_SA_CB<4>
  VSS24  = GND
  CB5_A  = M_H_CPU1_SA_CB<5>
  VSS25  = GND
  ALERT_N  = M_H_CPU1_ALERT_N
  VSS26  = GND
  CS0_A_N  = M_H_CPU1_SA_CS_N<0>
  VSS27  = GND
  CA0_A  = M_H_CPU1_SA_CA<0>
  VSS28  = GND
  CA2_A  = M_H_CPU1_SA_CA<2>
  VSS29  = GND
  CA4_A  = M_H_CPU1_SA_CA<4>
  VSS30  = GND
  CA6_A  = M_H_CPU1_SA_CA<6>
  VSS31  = GND
  PAR_A  = M_H_CPU1_SA_PAR
  VSS32  = GND
  CA0_B  = M_H_CPU1_SB_CA<0>
  VSS33  = GND
  CA2_B  = M_H_CPU1_SB_CA<2>
  VSS34  = GND
  CA4_B  = M_H_CPU1_SB_CA<4>
  VSS35  = GND
  CA6_B  = M_H_CPU1_SB_CA<6>
  VSS36  = GND
  CS0_B_N  = M_H_CPU1_SB_CS_N<0>
  VSS37  = GND
  \lbd||rsp_a_n\  = M_H_CPU1_SA_RSP<0>
  \lbs||rsp_b_n\  = M_H_CPU1_SB_RSP<0>
  VSS38  = GND
  CB4_B  = M_H_CPU1_SB_CB<4>
  VSS39  = GND
  CB5_B  = M_H_CPU1_SB_CB<5>
  VSS40  = GND
  \dqs9_b_t||tdqs9_b_t||dbi4_b_n\  = M_H_CPU1_SB_DQS_DP<9>
  \dqs9_b_c||tdqs9_b_c\  = M_H_CPU1_SB_DQS_DN<9>
  VSS41  = GND
  CB0_B  = M_H_CPU1_SB_CB<0>
  VSS42  = GND
  CB1_B  = M_H_CPU1_SB_CB<1>
  VSS43  = GND
  DQ0_B  = M_H_CPU1_SB_DQ<0>
  VSS44  = GND
  DQ1_B  = M_H_CPU1_SB_DQ<1>
  VSS45  = GND
  DQS0_B_T  = M_H_CPU1_SB_DQS_DP<0>
  DQS0_B_C  = M_H_CPU1_SB_DQS_DN<0>
  VSS46  = GND
  DQ4_B  = M_H_CPU1_SB_DQ<4>
  VSS47  = GND
  DQ5_B  = M_H_CPU1_SB_DQ<5>
  VSS48  = GND
  DQ8_B  = M_H_CPU1_SB_DQ<8>
  VSS49  = GND
  DQ9_B  = M_H_CPU1_SB_DQ<9>
  VSS50  = GND
  DQS1_B_T  = M_H_CPU1_SB_DQS_DP<1>
  DQS1_B_C  = M_H_CPU1_SB_DQS_DN<1>
  VSS51  = GND
  DQ12_B  = M_H_CPU1_SB_DQ<12>
  VSS52  = GND
  DQ13_B  = M_H_CPU1_SB_DQ<13>
  VSS53  = GND
  DQ16_B  = M_H_CPU1_SB_DQ<16>
  VSS54  = GND
  DQ17_B  = M_H_CPU1_SB_DQ<17>
  VSS55  = GND
  DQS2_B_T  = M_H_CPU1_SB_DQS_DP<2>
  DQS2_B_C  = M_H_CPU1_SB_DQS_DN<2>
  VSS56  = GND
  DQ20_B  = M_H_CPU1_SB_DQ<20>
  VSS57  = GND
  DQ21_B  = M_H_CPU1_SB_DQ<21>
  VSS58  = GND
  DQ24_B  = M_H_CPU1_SB_DQ<24>
  VSS59  = GND
  DQ25_B  = M_H_CPU1_SB_DQ<25>
  VSS60  = GND
  DQS3_B_T  = M_H_CPU1_SB_DQS_DP<3>
  DQS3_B_C  = M_H_CPU1_SB_DQS_DN<3>
  VSS61  = GND
  DQ28_B  = M_H_CPU1_SB_DQ<28>
  VSS62  = GND
  DQ29_B  = M_H_CPU1_SB_DQ<29>
  VSS63  = GND
  RFU1  = TP_CHH_CPU1_DIMM1_FRU_1
  VIN_BULK1  = P12V_S3_AUX_CPU1_NVDIMM
  VIN_BULK2  = P12V_S3_AUX_CPU1_NVDIMM
  \pwr_good||fail_n\  = PWRGD_CHH_CPU1_DIMM1
  HSA  = PD_CHH_CPU1_DIMM1_SAA
  RFU2  = TP_CHH_CPU1_DIMM1_FRU_2
  RFU3  = TP_CHH_CPU1_DIMM1_FRU_3
  VSS64  = GND
  DQ2_A  = M_H_CPU1_SA_DQ<2>
  VSS65  = GND
  DQ3_A  = M_H_CPU1_SA_DQ<3>
  VSS66  = GND
  \dqs5_a_c||tdqs5_a_c||dqs5_a_t||tdqs5_a_t\  = M_H_CPU1_SA_DQS_DN<5>
  \dqs5_a_t||tdqs5_a_t\  = M_H_CPU1_SA_DQS_DP<5>
  VSS67  = GND
  DQ6_A  = M_H_CPU1_SA_DQ<6>
  VSS68  = GND
  DQ7_A  = M_H_CPU1_SA_DQ<7>
  VSS69  = GND
  DQ10_A  = M_H_CPU1_SA_DQ<10>
  VSS70  = GND
  DQ11_A  = M_H_CPU1_SA_DQ<11>
  VSS71  = GND
  \dqs6_a_c||tdqs6_a_c||dqs6_a_t||tdqs6_a_t\  = M_H_CPU1_SA_DQS_DN<6>
  \dqs6_a_t||tdqs6_a_t\  = M_H_CPU1_SA_DQS_DP<6>
  VSS72  = GND
  DQ14_A  = M_H_CPU1_SA_DQ<14>
  VSS73  = GND
  DQ15_A  = M_H_CPU1_SA_DQ<15>
  VSS74  = GND
  DQ18_A  = M_H_CPU1_SA_DQ<18>
  VSS75  = GND
  DQ19_A  = M_H_CPU1_SA_DQ<19>
  VSS76  = GND
  \dqs7_a_c||tdqs7_a_c\  = M_H_CPU1_SA_DQS_DN<7>
  \dqs7_a_t||tdqs7_a_t\  = M_H_CPU1_SA_DQS_DP<7>
  VSS77  = GND
  DQ22_A  = M_H_CPU1_SA_DQ<22>
  VSS78  = GND
  DQ23_A  = M_H_CPU1_SA_DQ<23>
  VSS79  = GND
  DQ26_A  = M_H_CPU1_SA_DQ<26>
  VSS80  = GND
  DQ27_A  = M_H_CPU1_SA_DQ<27>
  VSS81  = GND
  \dqs8_a_c||tdqs8_a_c\  = M_H_CPU1_SA_DQS_DN<8>
  \dqs8_a_t||tdqs8_a_t\  = M_H_CPU1_SA_DQS_DP<8>
  VSS82  = GND
  DQ30_A  = M_H_CPU1_SA_DQ<30>
  VSS83  = GND
  DQ31_A  = M_H_CPU1_SA_DQ<31>
  VSS84  = GND
  CB2_A  = M_H_CPU1_SA_CB<2>
  VSS85  = GND
  CB3_A  = M_H_CPU1_SA_CB<3>
  VSS86  = GND
  \dqs9_a_c||tdqs9_a_c\  = M_H_CPU1_SA_DQS_DN<9>
  \dqs9_a_t||tdqs9_a_t\  = M_H_CPU1_SA_DQS_DP<9>
  VSS87  = GND
  CB6_A  = M_H_CPU1_SA_CB<6>
  VSS88  = GND
  CB7_A  = M_H_CPU1_SA_CB<7>
  VSS89  = GND
  RESET_N  = RST_M_GH_CPU1_FPGA_N
  VSS90  = GND
  CS1_A_N  = M_H_CPU1_SA_CS_N<1>
  VSS91  = GND
  CA1_A  = M_H_CPU1_SA_CA<1>
  VSS92  = GND
  CA3_A  = M_H_CPU1_SA_CA<3>
  VSS93  = GND
  CA5_A  = M_H_CPU1_SA_CA<5>
  VSS94  = GND
  CK_T  = M_H_CPU1_CLK_DP<0>
  CK_C  = M_H_CPU1_CLK_DN<0>
  VSS95  = GND
  RFU4  = TP_CHH_CPU1_DIMM1_FRU_4
  CA1_B  = M_H_CPU1_SB_CA<1>
  VSS96  = GND
  CA3_B  = M_H_CPU1_SB_CA<3>
  VSS97  = GND
  CA5_B  = M_H_CPU1_SB_CA<5>
  VSS98  = GND
  PAR_B  = M_H_CPU1_SB_PAR
  VSS99  = GND
  CS1_B_N  = M_H_CPU1_SB_CS_N<1>
  VSS100  = GND
  RFU5  = TP_CHH_CPU1_DIMM1_FRU_5
  RFU6  = TP_CHH_CPU1_DIMM1_FRU_6
  VSS101  = GND
  CB6_B  = M_H_CPU1_SB_CB<6>
  VSS102  = GND
  CB7_B  = M_H_CPU1_SB_CB<7>
  VSS103  = GND
  DQS4_B_C  = M_H_CPU1_SB_DQS_DN<4>
  DQS4_B_T  = M_H_CPU1_SB_DQS_DP<4>
  VSS104  = GND
  CB2_B  = M_H_CPU1_SB_CB<2>
  VSS105  = GND
  CB3_B  = M_H_CPU1_SB_CB<3>
  VSS106  = GND
  DQ2_B  = M_H_CPU1_SB_DQ<2>
  VSS107  = GND
  DQ3_B  = M_H_CPU1_SB_DQ<3>
  VSS108  = GND
  \dqs5_b_c||tdqs5_b_c\  = M_H_CPU1_SB_DQS_DN<5>
  \dqs5_b_t||tdqs5_b_t\  = M_H_CPU1_SB_DQS_DP<5>
  VSS109  = GND
  DQ6_B  = M_H_CPU1_SB_DQ<6>
  VSS110  = GND
  DQ7_B  = M_H_CPU1_SB_DQ<7>
  VSS111  = GND
  DQ10_B  = M_H_CPU1_SB_DQ<10>
  VSS112  = GND
  DQ11_B  = M_H_CPU1_SB_DQ<11>
  VSS113  = GND
  \dqs6_b_c||tdqs6_b_c\  = M_H_CPU1_SB_DQS_DN<6>
  \dqs6_b_t||tdqs6_b_t\  = M_H_CPU1_SB_DQS_DP<6>
  VSS114  = GND
  DQ14_B  = M_H_CPU1_SB_DQ<14>
  VSS115  = GND
  DQ15_B  = M_H_CPU1_SB_DQ<15>
  VSS116  = GND
  DQ18_B  = M_H_CPU1_SB_DQ<18>
  VSS117  = GND
  DQ19_B  = M_H_CPU1_SB_DQ<19>
  VSS118  = GND
  \dqs7_b_c||tdqs7_b_c\  = M_H_CPU1_SB_DQS_DN<7>
  \dqs7_b_t||tdqs7_b_t\  = M_H_CPU1_SB_DQS_DP<7>
  VSS119  = GND
  DQ22_B  = M_H_CPU1_SB_DQ<22>
  VSS120  = GND
  DQ23_B  = M_H_CPU1_SB_DQ<23>
  VSS121  = GND
  DQ26_B  = M_H_CPU1_SB_DQ<26>
  VSS122  = GND
  DQ27_B  = M_H_CPU1_SB_DQ<27>
  VSS123  = GND
  \dqs8_b_c||tdqs8_b_c\  = M_H_CPU1_SB_DQS_DN<8>
  \dqs8_b_t||tdqs8_b_t\  = M_H_CPU1_SB_DQS_DP<8>
  VSS124  = GND
  DQ30_B  = M_H_CPU1_SB_DQ<30>
  VSS125  = GND
  DQ31_B  = M_H_CPU1_SB_DQ<31>
  VSS126  = GND
  G1  = GND
  G2  = GND
  G3  = GND

(kicad_pcb
	(version 20260206)
	(generator "pcbnew")
	(generator_version "10.0")
	(general
		(thickness 1.6)
		(legacy_teardrops no)
	)
	(paper "A4")
	(title_block
		(title "03242023_DA0F0TMBIJ0_F0T_Motherboard_J_brd_V01_OCP.brd")
		(comment 1 "Grand Teton / footprint 3900 of 6105 (J31), pads 138-182 of 291")
	)
	(layers
		(0 "F.Cu" signal "TOP")
		(4 "In1.Cu" signal "GND")
		(6 "In2.Cu" signal "IN1")
		(8 "In3.Cu" signal "GND1")
		(10 "In4.Cu" signal "IN2")
		(12 "In5.Cu" signal "GND2")
		(14 "In6.Cu" signal "IN3")
		(16 "In7.Cu" signal "GND3")
		(18 "In8.Cu" signal "VCC")
		(20 "In9.Cu" signal "VCC1")
		(22 "In10.Cu" signal "GND4")
		(24 "In11.Cu" signal "IN4")
		(26 "In12.Cu" signal "GND5")
		(28 "In13.Cu" signal "IN5")
		(30 "In14.Cu" signal "GND6")
		(32 "In15.Cu" signal "IN6")
		(34 "In16.Cu" signal "GND7")
		(2 "B.Cu" signal "BOTTOM")
		(9 "F.Adhes" user "F.Adhesive")
		(11 "B.Adhes" user "B.Adhesive")
		(13 "F.Paste" user "Package Geometry/Pastemask Top")
		(15 "B.Paste" user "Package Geometry/Pastemask Bottom")
		(5 "F.SilkS" user "Ref Des/Silkscreen Top")
		(7 "B.SilkS" user "Ref Des/Silkscreen Bottom")
		(1 "F.Mask" user "Board Geometry/Soldermask Top")
		(3 "B.Mask" user "Board Geometry/Soldermask Bottom")
		(17 "Dwgs.User" user "User.Drawings")
		(19 "Cmts.User" user "User.Comments")
		(21 "Eco1.User" user "User.Eco1")
		(23 "Eco2.User" user "User.Eco2")
		(25 "Edge.Cuts" user "Board Geometry/Outline")
		(27 "Margin" user)
		(31 "F.CrtYd" user "Package Geometry/Place Bound Top")
		(29 "B.CrtYd" user "Package Geometry/Place Bound Bottom")
		(35 "F.Fab" user "Ref Des/Assembly Top")
		(33 "B.Fab" user "Ref Des/Assembly Bottom")
	)
	(footprint ""
		(layer "F.Cu")
		(at 213.66988 -258.091686)
		(property "Reference" "J31"
			(at -3.683 -81.702148 0)
			(unlocked yes)
			(layer "F.SilkS")
			(effects
				(font
					(size 0.7874 0.5842)
					(thickness 0.1524)
				)
				(justify left)
			)
		)
		(property "Value" ""
			(at 0 0 0)
			(layer "F.Fab")
			(effects
				(font
					(size 1.27 1.27)
				)
			)
		)
		(duplicate_pad_numbers_are_jumpers no)
		(pad "138" smd rect
			(at -2.050034 58.224928 270)
			(size 0.519938 1.4986)
			(layers "F.Cu" "F.Mask" "F.Paste")
			(net "M_H_CPU1_SB_DQS_DN<3>")
		)
		(pad "139" smd rect
			(at -2.050034 59.075066 270)
			(size 0.519938 1.4986)
			(layers "F.Cu" "F.Mask" "F.Paste")
			(net "GND")
		)
		(pad "140" smd rect
			(at -2.050034 59.92495 270)
			(size 0.519938 1.4986)
			(layers "F.Cu" "F.Mask" "F.Paste")
			(net "M_H_CPU1_SB_DQ<28>")
		)
		(pad "141" smd rect
			(at -2.050034 60.775088 270)
			(size 0.519938 1.4986)
			(layers "F.Cu" "F.Mask" "F.Paste")
			(net "GND")
		)
		(pad "142" smd rect
			(at -2.050034 61.624972 270)
			(size 0.519938 1.4986)
			(layers "F.Cu" "F.Mask" "F.Paste")
			(net "M_H_CPU1_SB_DQ<29>")
		)
		(pad "143" smd rect
			(at -2.050034 62.47511 270)
			(size 0.519938 1.4986)
			(layers "F.Cu" "F.Mask" "F.Paste")
			(net "GND")
		)
		(pad "144" smd rect
			(at -2.050034 63.324994 270)
			(size 0.519938 1.4986)
			(layers "F.Cu" "F.Mask" "F.Paste")
			(net "TP_CHH_CPU1_DIMM1_FRU_1")
		)
		(pad "145" smd rect
			(at 2.050034 -63.324994 270)
			(size 0.519938 1.4986)
			(layers "F.Cu" "F.Mask" "F.Paste")
			(net "P12V_S3_AUX_CPU1_NVDIMM")
		)
		(pad "146" smd rect
			(at 2.050034 -62.47511 270)
			(size 0.519938 1.4986)
			(layers "F.Cu" "F.Mask" "F.Paste")
			(net "P12V_S3_AUX_CPU1_NVDIMM")
		)
		(pad "147" smd rect
			(at 2.050034 -61.624972 270)
			(size 0.519938 1.4986)
			(layers "F.Cu" "F.Mask" "F.Paste")
			(net "PWRGD_CHH_CPU1_DIMM1")
		)
		(pad "148" smd rect
			(at 2.050034 -60.775088 270)
			(size 0.519938 1.4986)
			(layers "F.Cu" "F.Mask" "F.Paste")
			(net "PD_CHH_CPU1_DIMM1_SAA")
		)
		(pad "149" smd rect
			(at 2.050034 -59.92495 270)
			(size 0.519938 1.4986)
			(layers "F.Cu" "F.Mask" "F.Paste")
			(net "TP_CHH_CPU1_DIMM1_FRU_2")
		)
		(pad "150" smd rect
			(at 2.050034 -59.075066 270)
			(size 0.519938 1.4986)
			(layers "F.Cu" "F.Mask" "F.Paste")
			(net "TP_CHH_CPU1_DIMM1_FRU_3")
		)
		(pad "151" smd rect
			(at 2.050034 -58.224928 270)
			(size 0.519938 1.4986)
			(layers "F.Cu" "F.Mask" "F.Paste")
			(net "GND")
		)
		(pad "152" smd rect
			(at 2.050034 -57.375044 270)
			(size 0.519938 1.4986)
			(layers "F.Cu" "F.Mask" "F.Paste")
			(net "M_H_CPU1_SA_DQ<2>")
		)
		(pad "153" smd rect
			(at 2.050034 -56.524906 270)
			(size 0.519938 1.4986)
			(layers "F.Cu" "F.Mask" "F.Paste")
			(net "GND")
		)
		(pad "154" smd rect
			(at 2.050034 -55.675022 270)
			(size 0.519938 1.4986)
			(layers "F.Cu" "F.Mask" "F.Paste")
			(net "M_H_CPU1_SA_DQ<3>")
		)
		(pad "155" smd rect
			(at 2.050034 -54.824884 270)
			(size 0.519938 1.4986)
			(layers "F.Cu" "F.Mask" "F.Paste")
			(net "GND")
		)
		(pad "156" smd rect
			(at 2.050034 -53.975 270)
			(size 0.519938 1.4986)
			(layers "F.Cu" "F.Mask" "F.Paste")
			(net "M_H_CPU1_SA_DQS_DN<5>")
		)
		(pad "157" smd rect
			(at 2.050034 -53.125116 270)
			(size 0.519938 1.4986)
			(layers "F.Cu" "F.Mask" "F.Paste")
			(net "M_H_CPU1_SA_DQS_DP<5>")
		)
		(pad "158" smd rect
			(at 2.050034 -52.274978 270)
			(size 0.519938 1.4986)
			(layers "F.Cu" "F.Mask" "F.Paste")
			(net "GND")
		)
		(pad "159" smd rect
			(at 2.050034 -51.425094 270)
			(size 0.519938 1.4986)
			(layers "F.Cu" "F.Mask" "F.Paste")
			(net "M_H_CPU1_SA_DQ<6>")
		)
		(pad "160" smd rect
			(at 2.050034 -50.574956 270)
			(size 0.519938 1.4986)
			(layers "F.Cu" "F.Mask" "F.Paste")
			(net "GND")
		)
		(pad "161" smd rect
			(at 2.050034 -49.725072 270)
			(size 0.519938 1.4986)
			(layers "F.Cu" "F.Mask" "F.Paste")
			(net "M_H_CPU1_SA_DQ<7>")
		)
		(pad "162" smd rect
			(at 2.050034 -48.874934 270)
			(size 0.519938 1.4986)
			(layers "F.Cu" "F.Mask" "F.Paste")
			(net "GND")
		)
		(pad "163" smd rect
			(at 2.050034 -48.02505 270)
			(size 0.519938 1.4986)
			(layers "F.Cu" "F.Mask" "F.Paste")
			(net "M_H_CPU1_SA_DQ<10>")
		)
		(pad "164" smd rect
			(at 2.050034 -47.174912 270)
			(size 0.519938 1.4986)
			(layers "F.Cu" "F.Mask" "F.Paste")
			(net "GND")
		)
		(pad "165" smd rect
			(at 2.050034 -46.325028 270)
			(size 0.519938 1.4986)
			(layers "F.Cu" "F.Mask" "F.Paste")
			(net "M_H_CPU1_SA_DQ<11>")
		)
		(pad "166" smd rect
			(at 2.050034 -45.47489 270)
			(size 0.519938 1.4986)
			(layers "F.Cu" "F.Mask" "F.Paste")
			(net "GND")
		)
		(pad "167" smd rect
			(at 2.050034 -44.625006 270)
			(size 0.519938 1.4986)
			(layers "F.Cu" "F.Mask" "F.Paste")
			(net "M_H_CPU1_SA_DQS_DN<6>")
		)
		(pad "168" smd rect
			(at 2.050034 -43.775122 270)
			(size 0.519938 1.4986)
			(layers "F.Cu" "F.Mask" "F.Paste")
			(net "M_H_CPU1_SA_DQS_DP<6>")
		)
		(pad "169" smd rect
			(at 2.050034 -42.924984 270)
			(size 0.519938 1.4986)
			(layers "F.Cu" "F.Mask" "F.Paste")
			(net "GND")
		)
		(pad "170" smd rect
			(at 2.050034 -42.0751 270)
			(size 0.519938 1.4986)
			(layers "F.Cu" "F.Mask" "F.Paste")
			(net "M_H_CPU1_SA_DQ<14>")
		)
		(pad "171" smd rect
			(at 2.050034 -41.224962 270)
			(size 0.519938 1.4986)
			(layers "F.Cu" "F.Mask" "F.Paste")
			(net "GND")
		)
		(pad "172" smd rect
			(at 2.050034 -40.375078 270)
			(size 0.519938 1.4986)
			(layers "F.Cu" "F.Mask" "F.Paste")
			(net "M_H_CPU1_SA_DQ<15>")
		)
		(pad "173" smd rect
			(at 2.050034 -39.52494 270)
			(size 0.519938 1.4986)
			(layers "F.Cu" "F.Mask" "F.Paste")
			(net "GND")
		)
		(pad "174" smd rect
			(at 2.050034 -38.675056 270)
			(size 0.519938 1.4986)
			(layers "F.Cu" "F.Mask" "F.Paste")
			(net "M_H_CPU1_SA_DQ<18>")
		)
		(pad "175" smd rect
			(at 2.050034 -37.824918 270)
			(size 0.519938 1.4986)
			(layers "F.Cu" "F.Mask" "F.Paste")
			(net "GND")
		)
		(pad "176" smd rect
			(at 2.050034 -36.975034 270)
			(size 0.519938 1.4986)
			(layers "F.Cu" "F.Mask" "F.Paste")
			(net "M_H_CPU1_SA_DQ<19>")
		)
		(pad "177" smd rect
			(at 2.050034 -36.124896 270)
			(size 0.519938 1.4986)
			(layers "F.Cu" "F.Mask" "F.Paste")
			(net "GND")
		)
		(pad "178" smd rect
			(at 2.050034 -35.275012 270)
			(size 0.519938 1.4986)
			(layers "F.Cu" "F.Mask" "F.Paste")
			(net "M_H_CPU1_SA_DQS_DN<7>")
		)
		(pad "179" smd rect
			(at 2.050034 -34.425128 270)
			(size 0.519938 1.4986)
			(layers "F.Cu" "F.Mask" "F.Paste")
			(net "M_H_CPU1_SA_DQS_DP<7>")
		)
		(pad "180" smd rect
			(at 2.050034 -33.57499 270)
			(size 0.519938 1.4986)
			(layers "F.Cu" "F.Mask" "F.Paste")
			(net "GND")
		)
		(pad "181" smd rect
			(at 2.050034 -32.725106 270)
			(size 0.519938 1.4986)
			(layers "F.Cu" "F.Mask" "F.Paste")
			(net "M_H_CPU1_SA_DQ<22>")
		)
		(pad "182" smd rect
			(at 2.050034 -31.874968 270)
			(size 0.519938 1.4986)
			(layers "F.Cu" "F.Mask" "F.Paste")
			(net "GND")
		)
	)
)
